(kicad_pcb
	(version 20260206)
	(generator "pcbnew")
	(generator_version "10.0")
	(general
		(thickness 1.6)
		(legacy_teardrops no)
	)
	(paper "A4")
	(title_block
		(title "v1-chassis-manager — T6M_CM_d_v01_1031_1645.brd")
		(comment 1 "Open CloudServer (Microsoft) / footprints 1418-1427 of 2512")
	)
	(layers
		(0 "F.Cu" signal "TOP")
		(4 "In1.Cu" signal "GND1")
		(6 "In2.Cu" signal "IN1")
		(8 "In3.Cu" signal "VCC1")
		(10 "In4.Cu" signal "VCC2")
		(12 "In5.Cu" signal "GND2")
		(14 "In6.Cu" signal "IN2")
		(16 "In7.Cu" signal "IN3")
		(18 "In8.Cu" signal "GND3")
		(2 "B.Cu" signal "BOTTOM")
		(9 "F.Adhes" user "F.Adhesive")
		(11 "B.Adhes" user "B.Adhesive")
		(13 "F.Paste" user "Package Geometry/Pastemask Top")
		(15 "B.Paste" user "Package Geometry/Pastemask Bottom")
		(5 "F.SilkS" user "Ref Des/Silkscreen Top")
		(7 "B.SilkS" user "Ref Des/Silkscreen Bottom")
		(1 "F.Mask" user "Board Geometry/Soldermask Top")
		(3 "B.Mask" user "Board Geometry/Soldermask Bottom")
		(17 "Dwgs.User" user "User.Drawings")
		(19 "Cmts.User" user "User.Comments")
		(21 "Eco1.User" user "User.Eco1")
		(23 "Eco2.User" user "User.Eco2")
		(25 "Edge.Cuts" user "Board Geometry/Outline")
		(27 "Margin" user)
		(31 "F.CrtYd" user "Package Geometry/Place Bound Top")
		(29 "B.CrtYd" user "Package Geometry/Place Bound Bottom")
		(35 "F.Fab" user "Ref Des/Assembly Top")
		(33 "B.Fab" user "Ref Des/Assembly Bottom")
	)
	(footprint ""
		(layer "F.Cu")
		(at 169.792396 -61.68263)
		(property "Reference" "R270"
			(at -0.427736 -2.219452 0)
			(unlocked yes)
			(layer "F.SilkS")
			(effects
				(font
					(size 0.7874 0.5842)
					(thickness 0.1524)
				)
				(justify left)
			)
		)
		(property "Value" ""
			(at 0 0 0)
			(layer "F.Fab")
			(effects
				(font
					(size 1.27 1.27)
				)
			)
		)
		(duplicate_pad_numbers_are_jumpers no)
		(fp_line
			(start -0.7874 -0.4064)
			(end 0.7874 -0.4064)
			(stroke
				(width 0.1524)
				(type default)
			)
			(layer "F.SilkS")
		)
		(fp_line
			(start -0.7874 0.4064)
			(end -0.7874 -0.4064)
			(stroke
				(width 0.1524)
				(type default)
			)
			(layer "F.SilkS")
		)
		(fp_line
			(start 0.7874 -0.4064)
			(end 0.7874 0.4064)
			(stroke
				(width 0.1524)
				(type default)
			)
			(layer "F.SilkS")
		)
		(fp_line
			(start 0.7874 0.4064)
			(end -0.7874 0.4064)
			(stroke
				(width 0.1524)
				(type default)
			)
			(layer "F.SilkS")
		)
		(fp_poly
			(pts
				(xy -0.508 0.2794) (xy -0.508 0.2286) (xy -0.635 0.2286) (xy -0.635 -0.254) (xy -0.5334 -0.254)
				(xy -0.5334 -0.2794) (xy 0.5334 -0.2794) (xy 0.5334 -0.254) (xy 0.635 -0.254) (xy 0.635 0.254) (xy 0.5334 0.254)
				(xy 0.5334 0.2794)
			)
			(stroke
				(width 0)
				(type default)
			)
			(fill no)
			(layer "F.CrtYd")
		)
		(pad "1" smd rect
			(at 0.40005 0)
			(size 0.4572 0.508)
			(layers "F.Cu" "F.Mask" "F.Paste")
			(net "USB3_L_DP")
		)
		(pad "2" smd rect
			(at -0.40005 0)
			(size 0.4572 0.508)
			(layers "F.Cu" "F.Mask" "F.Paste")
			(net "USB3_DP")
		)
	)
	(footprint ""
		(layer "F.Cu")
		(at 160.154874 -165.753288 -90)
		(property "Reference" "U38"
			(at -3.253232 1.430528 0)
			(unlocked yes)
			(layer "F.SilkS")
			(effects
				(font
					(size 0.7874 0.5842)
					(thickness 0.1524)
				)
				(justify left)
			)
		)
		(property "Value" ""
			(at 0 0 270)
			(layer "F.Fab")
			(effects
				(font
					(size 1.27 1.27)
				)
			)
		)
		(duplicate_pad_numbers_are_jumpers no)
		(fp_line
			(start -2.5146 1.4224)
			(end -2.5146 0.4572)
			(stroke
				(width 0.1524)
				(type default)
			)
			(layer "F.SilkS")
		)
		(fp_line
			(start 2.5146 1.4224)
			(end -2.5146 1.4224)
			(stroke
				(width 0.1524)
				(type default)
			)
			(layer "F.SilkS")
		)
		(fp_line
			(start -2.5146 0.4572)
			(end -2.0574 0)
			(stroke
				(width 0.1524)
				(type default)
			)
			(layer "F.SilkS")
		)
		(fp_line
			(start -2.0574 0)
			(end -2.5146 -0.4572)
			(stroke
				(width 0.1524)
				(type default)
			)
			(layer "F.SilkS")
		)
		(fp_line
			(start -2.5146 -0.4572)
			(end -2.5146 -1.4224)
			(stroke
				(width 0.1524)
				(type default)
			)
			(layer "F.SilkS")
		)
		(fp_line
			(start -2.5146 -1.4224)
			(end 2.5146 -1.4224)
			(stroke
				(width 0.1524)
				(type default)
			)
			(layer "F.SilkS")
		)
		(fp_line
			(start 2.5146 -1.4224)
			(end 2.5146 1.4224)
			(stroke
				(width 0.1524)
				(type default)
			)
			(layer "F.SilkS")
		)
		(fp_circle
			(center -1.905 0.889)
			(end -1.905 0.635)
			(stroke
				(width 0.1524)
				(type default)
			)
			(fill no)
			(layer "F.SilkS")
		)
		(fp_poly
			(pts
				(xy -2.1844 3.5052) (xy -2.1844 2.0066) (xy -2.5146 2.0066) (xy -2.5146 -2.0066) (xy -2.1844 -2.0066)
				(xy -2.1844 -3.5052) (xy 2.1844 -3.5052) (xy 2.1844 -2.0066) (xy 2.5146 -2.0066) (xy 2.5146 2.0066)
				(xy 2.1844 2.0066) (xy 2.1844 3.5052)
			)
			(stroke
				(width 0)
				(type default)
			)
			(fill no)
			(layer "F.CrtYd")
		)
		(pad "1" smd rect
			(at -1.905 2.6416 270)
			(size 0.5588 1.7272)
			(layers "F.Cu" "F.Mask" "F.Paste")
			(net "LAN2_NVM_CS_N_R")
		)
		(pad "2" smd rect
			(at -0.635 2.6416 270)
			(size 0.5588 1.7272)
			(layers "F.Cu" "F.Mask" "F.Paste")
			(net "LAN2_NVM_SO_R")
		)
		(pad "3" smd rect
			(at 0.635 2.6416 270)
			(size 0.5588 1.7272)
			(layers "F.Cu" "F.Mask" "F.Paste")
			(net "LAN2_NVM_WP_N")
		)
		(pad "4" smd rect
			(at 1.905 2.6416 270)
			(size 0.5588 1.7272)
			(layers "F.Cu" "F.Mask" "F.Paste")
			(net "GND")
		)
		(pad "5" smd rect
			(at 1.905 -2.6416 270)
			(size 0.5588 1.7272)
			(layers "F.Cu" "F.Mask" "F.Paste")
			(net "LAN2_NVM_SI_R")
		)
		(pad "6" smd rect
			(at 0.635 -2.6416 270)
			(size 0.5588 1.7272)
			(layers "F.Cu" "F.Mask" "F.Paste")
			(net "LAN2_NVM_SK_R")
		)
		(pad "7" smd rect
			(at -0.635 -2.6416 270)
			(size 0.5588 1.7272)
			(layers "F.Cu" "F.Mask" "F.Paste")
			(net "LAN2_NVM_HOLD_N")
		)
		(pad "8" smd rect
			(at -1.905 -2.6416 270)
			(size 0.5588 1.7272)
			(layers "F.Cu" "F.Mask" "F.Paste")
			(net "P3V3_NODE1")
		)
	)
	(footprint ""
		(layer "F.Cu")
		(at 7.18058 -154.13736 -90)
		(property "Reference" "R1298"
			(at 5.109464 -8.825992 90)
			(unlocked yes)
			(layer "F.SilkS")
			(effects
				(font
					(size 0.7874 0.5842)
					(thickness 0.1524)
				)
				(justify left)
			)
		)
		(property "Value" ""
			(at 0 0 270)
			(layer "F.Fab")
			(effects
				(font
					(size 1.27 1.27)
				)
			)
		)
		(duplicate_pad_numbers_are_jumpers no)
		(fp_line
			(start -0.7874 0.4064)
			(end -0.7874 -0.4064)
			(stroke
				(width 0.1524)
				(type default)
			)
			(layer "F.SilkS")
		)
		(fp_line
			(start 0.7874 0.4064)
			(end -0.7874 0.4064)
			(stroke
				(width 0.1524)
				(type default)
			)
			(layer "F.SilkS")
		)
		(fp_line
			(start -0.7874 -0.4064)
			(end 0.7874 -0.4064)
			(stroke
				(width 0.1524)
				(type default)
			)
			(layer "F.SilkS")
		)
		(fp_line
			(start 0.7874 -0.4064)
			(end 0.7874 0.4064)
			(stroke
				(width 0.1524)
				(type default)
			)
			(layer "F.SilkS")
		)
		(fp_poly
			(pts
				(xy -0.508 0.2794) (xy -0.508 0.2286) (xy -0.635 0.2286) (xy -0.635 -0.254) (xy -0.5334 -0.254)
				(xy -0.5334 -0.2794) (xy 0.5334 -0.2794) (xy 0.5334 -0.254) (xy 0.635 -0.254) (xy 0.635 0.254) (xy 0.5334 0.254)
				(xy 0.5334 0.2794)
			)
			(stroke
				(width 0)
				(type default)
			)
			(fill no)
			(layer "F.CrtYd")
		)
		(pad "1" smd rect
			(at 0.40005 0 270)
			(size 0.4572 0.508)
			(layers "F.Cu" "F.Mask" "F.Paste")
			(net "P3V3_NODE1")
		)
		(pad "2" smd rect
			(at -0.40005 0 270)
			(size 0.4572 0.508)
			(layers "F.Cu" "F.Mask" "F.Paste")
			(net "N54258476")
		)
	)
	(footprint ""
		(layer "F.Cu")
		(at 106.170476 -173.004988 180)
		(property "Reference" "R760"
			(at -1.206754 -0.196342 0)
			(unlocked yes)
			(layer "F.SilkS")
			(effects
				(font
					(size 0.7874 0.5842)
					(thickness 0.1524)
				)
				(justify left)
			)
		)
		(property "Value" ""
			(at 0 0 180)
			(layer "F.Fab")
			(effects
				(font
					(size 1.27 1.27)
				)
			)
		)
		(duplicate_pad_numbers_are_jumpers no)
		(fp_line
			(start 0.7874 0.4064)
			(end -0.7874 0.4064)
			(stroke
				(width 0.1524)
				(type default)
			)
			(layer "F.SilkS")
		)
		(fp_line
			(start 0.7874 -0.4064)
			(end 0.7874 0.4064)
			(stroke
				(width 0.1524)
				(type default)
			)
			(layer "F.SilkS")
		)
		(fp_line
			(start -0.7874 0.4064)
			(end -0.7874 -0.4064)
			(stroke
				(width 0.1524)
				(type default)
			)
			(layer "F.SilkS")
		)
		(fp_line
			(start -0.7874 -0.4064)
			(end 0.7874 -0.4064)
			(stroke
				(width 0.1524)
				(type default)
			)
			(layer "F.SilkS")
		)
		(fp_poly
			(pts
				(xy -0.508 0.2794) (xy -0.508 0.2286) (xy -0.635 0.2286) (xy -0.635 -0.254) (xy -0.5334 -0.254)
				(xy -0.5334 -0.2794) (xy 0.5334 -0.2794) (xy 0.5334 -0.254) (xy 0.635 -0.254) (xy 0.635 0.254) (xy 0.5334 0.254)
				(xy 0.5334 0.2794)
			)
			(stroke
				(width 0)
				(type default)
			)
			(fill no)
			(layer "F.CrtYd")
		)
		(pad "1" smd rect
			(at 0.40005 0 180)
			(size 0.4572 0.508)
			(layers "F.Cu" "F.Mask" "F.Paste")
			(net "I2C_ALERT_FNACTRL1_N")
		)
		(pad "2" smd rect
			(at -0.40005 0 180)
			(size 0.4572 0.508)
			(layers "F.Cu" "F.Mask" "F.Paste")
			(net "P3V3_NODE1")
		)
	)
	(footprint ""
		(layer "F.Cu")
		(at 130.98145 -60.930282 90)
		(property "Reference" "R516"
			(at -1.037082 -2.22758 90)
			(unlocked yes)
			(layer "F.SilkS")
			(effects
				(font
					(size 0.7874 0.5842)
					(thickness 0.1524)
				)
				(justify left)
			)
		)
		(property "Value" ""
			(at 0 0 90)
			(layer "F.Fab")
			(effects
				(font
					(size 1.27 1.27)
				)
			)
		)
		(duplicate_pad_numbers_are_jumpers no)
		(fp_line
			(start 0.7874 -0.4064)
			(end 0.7874 0.4064)
			(stroke
				(width 0.1524)
				(type default)
			)
			(layer "F.SilkS")
		)
		(fp_line
			(start -0.7874 -0.4064)
			(end 0.7874 -0.4064)
			(stroke
				(width 0.1524)
				(type default)
			)
			(layer "F.SilkS")
		)
		(fp_line
			(start 0.7874 0.4064)
			(end -0.7874 0.4064)
			(stroke
				(width 0.1524)
				(type default)
			)
			(layer "F.SilkS")
		)
		(fp_line
			(start -0.7874 0.4064)
			(end -0.7874 -0.4064)
			(stroke
				(width 0.1524)
				(type default)
			)
			(layer "F.SilkS")
		)
		(fp_poly
			(pts
				(xy -0.508 0.2794) (xy -0.508 0.2286) (xy -0.635 0.2286) (xy -0.635 -0.254) (xy -0.5334 -0.254)
				(xy -0.5334 -0.2794) (xy 0.5334 -0.2794) (xy 0.5334 -0.254) (xy 0.635 -0.254) (xy 0.635 0.254) (xy 0.5334 0.254)
				(xy 0.5334 0.2794)
			)
			(stroke
				(width 0)
				(type default)
			)
			(fill no)
			(layer "F.CrtYd")
		)
		(pad "1" smd rect
			(at 0.40005 0 90)
			(size 0.4572 0.508)
			(layers "F.Cu" "F.Mask" "F.Paste")
			(net "SATA_SPI_DI_NODE1_R")
		)
		(pad "2" smd rect
			(at -0.40005 0 90)
			(size 0.4572 0.508)
			(layers "F.Cu" "F.Mask" "F.Paste")
			(net "P3V3_NODE1")
		)
	)
	(footprint ""
		(layer "F.Cu")
		(at 25.999948 -88.799924)
		(property "Reference" "H1"
			(at 2.265172 -2.582164 0)
			(unlocked yes)
			(layer "F.SilkS")
			(effects
				(font
					(size 0.7874 0.5842)
					(thickness 0.1524)
				)
				(justify left)
			)
		)
		(property "Value" ""
			(at 0 0 0)
			(layer "F.Fab")
			(effects
				(font
					(size 1.27 1.27)
				)
			)
		)
		(duplicate_pad_numbers_are_jumpers no)
		(fp_circle
			(center 0 0)
			(end 2.3114 0)
			(stroke
				(width 0.1524)
				(type default)
			)
			(fill no)
			(layer "F.SilkS")
		)
		(fp_circle
			(center 0 0)
			(end 2.3114 0)
			(stroke
				(width 0.1524)
				(type default)
			)
			(fill no)
			(layer "B.SilkS")
		)
		(fp_poly
			(pts
				(arc
					(start 0 1.4986)
					(mid 0 -1.4986)
					(end 0 1.4986)
				)
			)
			(stroke
				(width 0)
				(type default)
			)
			(fill no)
			(layer "F.CrtYd")
		)
		(pad "" np_thru_hole circle
			(at 0 0)
			(size 2.9972 2.9972)
			(drill 2.9972)
			(layers "*.Cu" "*.Mask")
			(clearance 0.381)
			(thermal_gap 0.381)
		)
		(zone
			(layers "F.Cu" "B.Cu" "In1.Cu" "In2.Cu" "In3.Cu" "In4.Cu" "In5.Cu" "In6.Cu"
				"In7.Cu" "In8.Cu"
			)
			(hatch none 0.5)
			(connect_pads
				(clearance 0)
			)
			(min_thickness 0.25)
			(keepout
				(tracks not_allowed)
				(vias allowed)
				(pads allowed)
				(copperpour not_allowed)
				(footprints allowed)
			)
			(placement
				(enabled no)
				(sheetname "")
			)
			(fill
				(thermal_gap 0.5)
				(thermal_bridge_width 0.5)
				(island_removal_mode 0)
			)
			(polygon
				(pts
					(arc
						(start 25.999948 -86.793324)
						(mid 25.999948 -90.806524)
						(end 25.999948 -86.793324)
					)
				)
			)
		)
	)
	(footprint ""
		(layer "F.Cu")
		(at 184.614566 -130.602228 -90)
		(property "Reference" "R1120"
			(at 1.003554 -13.856716 90)
			(unlocked yes)
			(layer "F.SilkS")
			(effects
				(font
					(size 0.7874 0.5842)
					(thickness 0.1524)
				)
				(justify left)
			)
		)
		(property "Value" ""
			(at 0 0 270)
			(layer "F.Fab")
			(effects
				(font
					(size 1.27 1.27)
				)
			)
		)
		(duplicate_pad_numbers_are_jumpers no)
		(fp_line
			(start -0.7874 0.4064)
			(end -0.7874 -0.4064)
			(stroke
				(width 0.1524)
				(type default)
			)
			(layer "F.SilkS")
		)
		(fp_line
			(start 0.7874 0.4064)
			(end -0.7874 0.4064)
			(stroke
				(width 0.1524)
				(type default)
			)
			(layer "F.SilkS")
		)
		(fp_line
			(start -0.7874 -0.4064)
			(end 0.7874 -0.4064)
			(stroke
				(width 0.1524)
				(type default)
			)
			(layer "F.SilkS")
		)
		(fp_line
			(start 0.7874 -0.4064)
			(end 0.7874 0.4064)
			(stroke
				(width 0.1524)
				(type default)
			)
			(layer "F.SilkS")
		)
		(fp_poly
			(pts
				(xy -0.508 0.2794) (xy -0.508 0.2286) (xy -0.635 0.2286) (xy -0.635 -0.254) (xy -0.5334 -0.254)
				(xy -0.5334 -0.2794) (xy 0.5334 -0.2794) (xy 0.5334 -0.254) (xy 0.635 -0.254) (xy 0.635 0.254) (xy 0.5334 0.254)
				(xy 0.5334 0.2794)
			)
			(stroke
				(width 0)
				(type default)
			)
			(fill no)
			(layer "F.CrtYd")
		)
		(pad "1" smd rect
			(at 0.40005 0 270)
			(size 0.4572 0.508)
			(layers "F.Cu" "F.Mask" "F.Paste")
			(net "SYS_AUTO_POWER_ON_N")
		)
		(pad "2" smd rect
			(at -0.40005 0 270)
			(size 0.4572 0.508)
			(layers "F.Cu" "F.Mask" "F.Paste")
			(net "GND")
		)
	)
	(footprint ""
		(layer "F.Cu")
		(at 162.549078 -12.4714 90)
		(property "Reference" "R1198"
			(at -0.888238 -2.062988 90)
			(unlocked yes)
			(layer "F.SilkS")
			(effects
				(font
					(size 0.7874 0.5842)
					(thickness 0.1524)
				)
				(justify left)
			)
		)
		(property "Value" ""
			(at 0 0 90)
			(layer "F.Fab")
			(effects
				(font
					(size 1.27 1.27)
				)
			)
		)
		(duplicate_pad_numbers_are_jumpers no)
		(fp_line
			(start 0.7874 -0.4064)
			(end 0.7874 0.4064)
			(stroke
				(width 0.1524)
				(type default)
			)
			(layer "F.SilkS")
		)
		(fp_line
			(start -0.7874 -0.4064)
			(end 0.7874 -0.4064)
			(stroke
				(width 0.1524)
				(type default)
			)
			(layer "F.SilkS")
		)
		(fp_line
			(start 0.7874 0.4064)
			(end -0.7874 0.4064)
			(stroke
				(width 0.1524)
				(type default)
			)
			(layer "F.SilkS")
		)
		(fp_line
			(start -0.7874 0.4064)
			(end -0.7874 -0.4064)
			(stroke
				(width 0.1524)
				(type default)
			)
			(layer "F.SilkS")
		)
		(fp_poly
			(pts
				(xy -0.508 0.2794) (xy -0.508 0.2286) (xy -0.635 0.2286) (xy -0.635 -0.254) (xy -0.5334 -0.254)
				(xy -0.5334 -0.2794) (xy 0.5334 -0.2794) (xy 0.5334 -0.254) (xy 0.635 -0.254) (xy 0.635 0.254) (xy 0.5334 0.254)
				(xy 0.5334 0.2794)
			)
			(stroke
				(width 0)
				(type default)
			)
			(fill no)
			(layer "F.CrtYd")
		)
		(pad "1" smd rect
			(at 0.40005 0 90)
			(size 0.4572 0.508)
			(layers "F.Cu" "F.Mask" "F.Paste")
			(net "SIO_JTAG_CPLD3_TDI")
		)
		(pad "2" smd rect
			(at -0.40005 0 90)
			(size 0.4572 0.508)
			(layers "F.Cu" "F.Mask" "F.Paste")
			(net "JTAG_CPLD3_TDI")
		)
	)
	(footprint ""
		(layer "F.Cu")
		(at 114.79276 -175.426624 90)
		(property "Reference" "R1058"
			(at -57.01538 33.114488 90)
			(unlocked yes)
			(layer "F.SilkS")
			(effects
				(font
					(size 0.7874 0.5842)
					(thickness 0.1524)
				)
				(justify left)
			)
		)
		(property "Value" ""
			(at 0 0 90)
			(layer "F.Fab")
			(effects
				(font
					(size 1.27 1.27)
				)
			)
		)
		(duplicate_pad_numbers_are_jumpers no)
		(fp_line
			(start 0.7874 -0.4064)
			(end 0.7874 0.4064)
			(stroke
				(width 0.1524)
				(type default)
			)
			(layer "F.SilkS")
		)
		(fp_line
			(start -0.7874 -0.4064)
			(end 0.7874 -0.4064)
			(stroke
				(width 0.1524)
				(type default)
			)
			(layer "F.SilkS")
		)
		(fp_line
			(start 0.7874 0.4064)
			(end -0.7874 0.4064)
			(stroke
				(width 0.1524)
				(type default)
			)
			(layer "F.SilkS")
		)
		(fp_line
			(start -0.7874 0.4064)
			(end -0.7874 -0.4064)
			(stroke
				(width 0.1524)
				(type default)
			)
			(layer "F.SilkS")
		)
		(fp_poly
			(pts
				(xy -0.508 0.2794) (xy -0.508 0.2286) (xy -0.635 0.2286) (xy -0.635 -0.254) (xy -0.5334 -0.254)
				(xy -0.5334 -0.2794) (xy 0.5334 -0.2794) (xy 0.5334 -0.254) (xy 0.635 -0.254) (xy 0.635 0.254) (xy 0.5334 0.254)
				(xy 0.5334 0.2794)
			)
			(stroke
				(width 0)
				(type default)
			)
			(fill no)
			(layer "F.CrtYd")
		)
		(pad "1" smd rect
			(at 0.40005 0 90)
			(size 0.4572 0.508)
			(layers "F.Cu" "F.Mask" "F.Paste")
			(net "N31348569")
		)
		(pad "2" smd rect
			(at -0.40005 0 90)
			(size 0.4572 0.508)
			(layers "F.Cu" "F.Mask" "F.Paste")
			(net "GND")
		)
	)
	(footprint ""
		(layer "F.Cu")
		(at 154.170888 -175.356266 90)
		(property "Reference" "R1305"
			(at 0.549148 -1.260348 90)
			(unlocked yes)
			(layer "F.SilkS")
			(effects
				(font
					(size 0.7874 0.5842)
					(thickness 0.1524)
				)
				(justify left)
			)
		)
		(property "Value" ""
			(at 0 0 90)
			(layer "F.Fab")
			(effects
				(font
					(size 1.27 1.27)
				)
			)
		)
		(duplicate_pad_numbers_are_jumpers no)
		(fp_line
			(start 0.7874 -0.4064)
			(end 0.7874 0.4064)
			(stroke
				(width 0.1524)
				(type default)
			)
			(layer "F.SilkS")
		)
		(fp_line
			(start -0.7874 -0.4064)
			(end 0.7874 -0.4064)
			(stroke
				(width 0.1524)
				(type default)
			)
			(layer "F.SilkS")
		)
		(fp_line
			(start 0.7874 0.4064)
			(end -0.7874 0.4064)
			(stroke
				(width 0.1524)
				(type default)
			)
			(layer "F.SilkS")
		)
		(fp_line
			(start -0.7874 0.4064)
			(end -0.7874 -0.4064)
			(stroke
				(width 0.1524)
				(type default)
			)
			(layer "F.SilkS")
		)
		(fp_poly
			(pts
				(xy -0.508 0.2794) (xy -0.508 0.2286) (xy -0.635 0.2286) (xy -0.635 -0.254) (xy -0.5334 -0.254)
				(xy -0.5334 -0.2794) (xy 0.5334 -0.2794) (xy 0.5334 -0.254) (xy 0.635 -0.254) (xy 0.635 0.254) (xy 0.5334 0.254)
				(xy 0.5334 0.2794)
			)
			(stroke
				(width 0)
				(type default)
			)
			(fill no)
			(layer "F.CrtYd")
		)
		(pad "1" smd rect
			(at 0.40005 0 90)
			(size 0.4572 0.508)
			(layers "F.Cu" "F.Mask" "F.Paste")
			(net "P3V3_NODE1")
		)
		(pad "2" smd rect
			(at -0.40005 0 90)
			(size 0.4572 0.508)
			(layers "F.Cu" "F.Mask" "F.Paste")
			(net "N54365554")
		)
	)
)
